(kicad_pcb
	(version 20260206)
	(generator "pcbnew")
	(generator_version "10.0")
	(general
		(thickness 1.6)
		(legacy_teardrops no)
	)
	(paper "A4")
	(title_block
		(title "01162023_DA0F0TEBIF0_F0T_Expander_BD_F_brd_V02_OCP.brd")
		(comment 1 "Grand Teton / footprints 7704-7711 of 9728")
	)
	(layers
		(0 "F.Cu" signal "TOP")
		(4 "In1.Cu" signal "GND")
		(6 "In2.Cu" signal "VCC")
		(8 "In3.Cu" signal "VCC1")
		(10 "In4.Cu" signal "GND1")
		(12 "In5.Cu" signal "IN1")
		(14 "In6.Cu" signal "GND2")
		(16 "In7.Cu" signal "IN2")
		(18 "In8.Cu" signal "GND3")
		(20 "In9.Cu" signal "IN3")
		(22 "In10.Cu" signal "GND4")
		(24 "In11.Cu" signal "IN4")
		(26 "In12.Cu" signal "GND5")
		(28 "In13.Cu" signal "IN5")
		(30 "In14.Cu" signal "GND6")
		(32 "In15.Cu" signal "IN6")
		(34 "In16.Cu" signal "GND7")
		(2 "B.Cu" signal "BOTTOM")
		(9 "F.Adhes" user "F.Adhesive")
		(11 "B.Adhes" user "B.Adhesive")
		(13 "F.Paste" user "Package Geometry/Pastemask Top")
		(15 "B.Paste" user "Package Geometry/Pastemask Bottom")
		(5 "F.SilkS" user "Ref Des/Silkscreen Top")
		(7 "B.SilkS" user "Ref Des/Silkscreen Bottom")
		(1 "F.Mask" user "Board Geometry/Soldermask Top")
		(3 "B.Mask" user "Board Geometry/Soldermask Bottom")
		(17 "Dwgs.User" user "User.Drawings")
		(19 "Cmts.User" user "User.Comments")
		(21 "Eco1.User" user "User.Eco1")
		(23 "Eco2.User" user "User.Eco2")
		(25 "Edge.Cuts" user "Board Geometry/Outline")
		(27 "Margin" user)
		(31 "F.CrtYd" user "Package Geometry/Place Bound Top")
		(29 "B.CrtYd" user "Package Geometry/Place Bound Bottom")
		(35 "F.Fab" user "Ref Des/Assembly Top")
		(33 "B.Fab" user "Ref Des/Assembly Bottom")
	)
	(footprint ""
		(layer "B.Cu")
		(at 112.672114 -258.004564 90)
		(property "Reference" "PR93"
			(at 0 0 90)
			(layer "B.SilkS")
			(hide yes)
			(effects
				(font
					(size 1.27 1.27)
				)
				(justify mirror)
			)
		)
		(property "Value" ""
			(at 0 0 90)
			(layer "B.Fab")
			(effects
				(font
					(size 1.27 1.27)
				)
				(justify mirror)
			)
		)
		(duplicate_pad_numbers_are_jumpers no)
		(fp_line
			(start 0.7874 -0.4064)
			(end -0.7874 -0.4064)
			(stroke
				(width 0.1524)
				(type default)
			)
			(layer "B.SilkS")
		)
		(fp_line
			(start -0.7874 -0.4064)
			(end -0.7874 0.4064)
			(stroke
				(width 0.1524)
				(type default)
			)
			(layer "B.SilkS")
		)
		(fp_line
			(start 0.7874 0.4064)
			(end 0.7874 -0.4064)
			(stroke
				(width 0.1524)
				(type default)
			)
			(layer "B.SilkS")
		)
		(fp_line
			(start -0.7874 0.4064)
			(end 0.7874 0.4064)
			(stroke
				(width 0.1524)
				(type default)
			)
			(layer "B.SilkS")
		)
		(fp_line
			(start 0.67945 -0.305054)
			(end 0.12065 -0.305054)
			(stroke
				(width 0.1)
				(type default)
			)
			(layer "B.Fab")
		)
		(fp_line
			(start 0.12065 -0.305054)
			(end 0.12065 -0.2794)
			(stroke
				(width 0.1)
				(type default)
			)
			(layer "B.Fab")
		)
		(fp_line
			(start -0.12065 -0.3048)
			(end -0.67945 -0.3048)
			(stroke
				(width 0.1)
				(type default)
			)
			(layer "B.Fab")
		)
		(fp_line
			(start -0.67945 -0.3048)
			(end -0.67945 0.3048)
			(stroke
				(width 0.1)
				(type default)
			)
			(layer "B.Fab")
		)
		(fp_line
			(start 0.12065 -0.2794)
			(end -0.12065 -0.2794)
			(stroke
				(width 0.1)
				(type default)
			)
			(layer "B.Fab")
		)
		(fp_line
			(start -0.12065 -0.2794)
			(end -0.12065 -0.3048)
			(stroke
				(width 0.1)
				(type default)
			)
			(layer "B.Fab")
		)
		(fp_line
			(start 0.12065 0.2794)
			(end 0.12065 0.3048)
			(stroke
				(width 0.1)
				(type default)
			)
			(layer "B.Fab")
		)
		(fp_line
			(start -0.120396 0.2794)
			(end 0.12065 0.2794)
			(stroke
				(width 0.1)
				(type default)
			)
			(layer "B.Fab")
		)
		(fp_line
			(start 0.67945 0.3048)
			(end 0.67945 -0.305054)
			(stroke
				(width 0.1)
				(type default)
			)
			(layer "B.Fab")
		)
		(fp_line
			(start 0.12065 0.3048)
			(end 0.67945 0.3048)
			(stroke
				(width 0.1)
				(type default)
			)
			(layer "B.Fab")
		)
		(fp_line
			(start -0.120396 0.3048)
			(end -0.120396 0.2794)
			(stroke
				(width 0.1)
				(type default)
			)
			(layer "B.Fab")
		)
		(fp_line
			(start -0.67945 0.3048)
			(end -0.120396 0.3048)
			(stroke
				(width 0.1)
				(type default)
			)
			(layer "B.Fab")
		)
		(pad "1" smd circle
			(at 0.40005 0 270)
			(size 0 0)
			(layers "B.Cu" "B.Mask" "B.Paste")
			(net "P12V_AUX")
		)
		(pad "2" smd circle
			(at -0.40005 0 270)
			(size 0 0)
			(layers "B.Cu" "B.Mask" "B.Paste")
			(net "P0V8_PEX0_IINSEN")
		)
	)
	(footprint ""
		(layer "B.Cu")
		(at 237.631986 -356.165658)
		(property "Reference" "PR7145"
			(at 0 0 0)
			(layer "B.SilkS")
			(hide yes)
			(effects
				(font
					(size 1.27 1.27)
				)
				(justify mirror)
			)
		)
		(property "Value" ""
			(at 0 0 0)
			(layer "B.Fab")
			(effects
				(font
					(size 1.27 1.27)
				)
				(justify mirror)
			)
		)
		(duplicate_pad_numbers_are_jumpers no)
		(fp_line
			(start -0.7874 -0.4064)
			(end -0.7874 0.4064)
			(stroke
				(width 0.1524)
				(type default)
			)
			(layer "B.SilkS")
		)
		(fp_line
			(start -0.7874 0.4064)
			(end 0.7874 0.4064)
			(stroke
				(width 0.1524)
				(type default)
			)
			(layer "B.SilkS")
		)
		(fp_line
			(start 0.7874 -0.4064)
			(end -0.7874 -0.4064)
			(stroke
				(width 0.1524)
				(type default)
			)
			(layer "B.SilkS")
		)
		(fp_line
			(start 0.7874 0.4064)
			(end 0.7874 -0.4064)
			(stroke
				(width 0.1524)
				(type default)
			)
			(layer "B.SilkS")
		)
		(fp_line
			(start -0.67945 -0.3048)
			(end -0.67945 0.3048)
			(stroke
				(width 0.1)
				(type default)
			)
			(layer "B.Fab")
		)
		(fp_line
			(start -0.67945 0.3048)
			(end -0.120396 0.3048)
			(stroke
				(width 0.1)
				(type default)
			)
			(layer "B.Fab")
		)
		(fp_line
			(start -0.12065 -0.3048)
			(end -0.67945 -0.3048)
			(stroke
				(width 0.1)
				(type default)
			)
			(layer "B.Fab")
		)
		(fp_line
			(start -0.12065 -0.2794)
			(end -0.12065 -0.3048)
			(stroke
				(width 0.1)
				(type default)
			)
			(layer "B.Fab")
		)
		(fp_line
			(start -0.120396 0.2794)
			(end 0.12065 0.2794)
			(stroke
				(width 0.1)
				(type default)
			)
			(layer "B.Fab")
		)
		(fp_line
			(start -0.120396 0.3048)
			(end -0.120396 0.2794)
			(stroke
				(width 0.1)
				(type default)
			)
			(layer "B.Fab")
		)
		(fp_line
			(start 0.12065 -0.305054)
			(end 0.12065 -0.2794)
			(stroke
				(width 0.1)
				(type default)
			)
			(layer "B.Fab")
		)
		(fp_line
			(start 0.12065 -0.2794)
			(end -0.12065 -0.2794)
			(stroke
				(width 0.1)
				(type default)
			)
			(layer "B.Fab")
		)
		(fp_line
			(start 0.12065 0.2794)
			(end 0.12065 0.3048)
			(stroke
				(width 0.1)
				(type default)
			)
			(layer "B.Fab")
		)
		(fp_line
			(start 0.12065 0.3048)
			(end 0.67945 0.3048)
			(stroke
				(width 0.1)
				(type default)
			)
			(layer "B.Fab")
		)
		(fp_line
			(start 0.67945 -0.305054)
			(end 0.12065 -0.305054)
			(stroke
				(width 0.1)
				(type default)
			)
			(layer "B.Fab")
		)
		(fp_line
			(start 0.67945 0.3048)
			(end 0.67945 -0.305054)
			(stroke
				(width 0.1)
				(type default)
			)
			(layer "B.Fab")
		)
		(pad "1" smd circle
			(at 0.40005 0 180)
			(size 0 0)
			(layers "B.Cu" "B.Mask" "B.Paste")
			(net "P12V_HSC_ADC_P")
		)
		(pad "2" smd circle
			(at -0.40005 0 180)
			(size 0 0)
			(layers "B.Cu" "B.Mask" "B.Paste")
			(net "P12V_HSC_SENSE2_R1_P")
		)
	)
	(footprint ""
		(layer "B.Cu")
		(at 283.299916 -292.099746 90)
		(property "Reference" "C1685"
			(at 0 0 90)
			(layer "B.SilkS")
			(hide yes)
			(effects
				(font
					(size 1.27 1.27)
				)
				(justify mirror)
			)
		)
		(property "Value" ""
			(at 0 0 90)
			(layer "B.Fab")
			(effects
				(font
					(size 1.27 1.27)
				)
				(justify mirror)
			)
		)
		(duplicate_pad_numbers_are_jumpers no)
		(fp_line
			(start 0.299974 -0.150114)
			(end -0.299974 -0.150114)
			(stroke
				(width 0.1)
				(type default)
			)
			(layer "B.Fab")
		)
		(fp_line
			(start -0.299974 -0.150114)
			(end -0.299974 0.150114)
			(stroke
				(width 0.1)
				(type default)
			)
			(layer "B.Fab")
		)
		(fp_line
			(start 0.299974 0.150114)
			(end 0.299974 -0.150114)
			(stroke
				(width 0.1)
				(type default)
			)
			(layer "B.Fab")
		)
		(fp_line
			(start -0.299974 0.150114)
			(end 0.299974 0.150114)
			(stroke
				(width 0.1)
				(type default)
			)
			(layer "B.Fab")
		)
		(pad "1" smd rect
			(at 0.2667 0 270)
			(size 0.3048 0.381)
			(layers "B.Cu" "B.Mask" "B.Paste")
			(net "P0V8_SERDES_VDDA_PEX2")
		)
		(pad "2" smd rect
			(at -0.2667 0 270)
			(size 0.3048 0.381)
			(layers "B.Cu" "B.Mask" "B.Paste")
			(net "GND")
		)
	)
	(footprint ""
		(layer "B.Cu")
		(at 344.8939 -223.187006 180)
		(property "Reference" "C2034"
			(at 0 0 0)
			(layer "B.SilkS")
			(hide yes)
			(effects
				(font
					(size 1.27 1.27)
				)
				(justify mirror)
			)
		)
		(property "Value" ""
			(at 0 0 0)
			(layer "B.Fab")
			(effects
				(font
					(size 1.27 1.27)
				)
				(justify mirror)
			)
		)
		(duplicate_pad_numbers_are_jumpers no)
		(fp_line
			(start 0.69215 0.2921)
			(end 0.69215 -0.2921)
			(stroke
				(width 0.1524)
				(type default)
			)
			(layer "B.SilkS")
		)
		(fp_line
			(start 0.69215 -0.2921)
			(end -0.69215 -0.2921)
			(stroke
				(width 0.1524)
				(type default)
			)
			(layer "B.SilkS")
		)
		(fp_line
			(start -0.69215 0.2921)
			(end 0.69215 0.2921)
			(stroke
				(width 0.1524)
				(type default)
			)
			(layer "B.SilkS")
		)
		(fp_line
			(start -0.69215 -0.2921)
			(end -0.69215 0.2921)
			(stroke
				(width 0.1524)
				(type default)
			)
			(layer "B.SilkS")
		)
		(fp_line
			(start 0.51435 0.2794)
			(end 0.51435 -0.2794)
			(stroke
				(width 0.1)
				(type default)
			)
			(layer "B.Fab")
		)
		(fp_line
			(start 0.51435 -0.2794)
			(end -0.51435 -0.2794)
			(stroke
				(width 0.1)
				(type default)
			)
			(layer "B.Fab")
		)
		(fp_line
			(start -0.51435 0.2794)
			(end 0.51435 0.2794)
			(stroke
				(width 0.1)
				(type default)
			)
			(layer "B.Fab")
		)
		(fp_line
			(start -0.51435 -0.2794)
			(end -0.51435 0.2794)
			(stroke
				(width 0.1)
				(type default)
			)
			(layer "B.Fab")
		)
		(pad "1" smd circle
			(at 0.40005 0)
			(size 0 0)
			(layers "B.Cu" "B.Mask" "B.Paste")
			(net "P3V3_FPGA_VCCIO0")
		)
		(pad "2" smd circle
			(at -0.40005 0)
			(size 0 0)
			(layers "B.Cu" "B.Mask" "B.Paste")
			(net "GND")
		)
		(zone
			(layer "B.Cu")
			(hatch none 0.5)
			(connect_pads
				(clearance 0)
			)
			(min_thickness 0.25)
			(keepout
				(tracks not_allowed)
				(vias allowed)
				(pads allowed)
				(copperpour not_allowed)
				(footprints allowed)
			)
			(placement
				(enabled no)
				(sheetname "")
			)
			(fill
				(thermal_gap 0.5)
				(thermal_bridge_width 0.5)
				(island_removal_mode 0)
			)
			(polygon
				(pts
					(xy 344.7034 -223.274636) (xy 344.79484 -223.332802) (xy 344.99423 -223.332802) (xy 345.0844 -223.274636)
					(xy 345.0844 -223.099376) (xy 344.99423 -223.040956) (xy 344.79484 -223.040956) (xy 344.7034 -223.099122)
				)
			)
		)
	)
	(footprint ""
		(layer "B.Cu")
		(at 300.012354 -234.958636 90)
		(property "Reference" "R1864"
			(at 0 0 90)
			(layer "B.SilkS")
			(hide yes)
			(effects
				(font
					(size 1.27 1.27)
				)
				(justify mirror)
			)
		)
		(property "Value" ""
			(at 0 0 90)
			(layer "B.Fab")
			(effects
				(font
					(size 1.27 1.27)
				)
				(justify mirror)
			)
		)
		(duplicate_pad_numbers_are_jumpers no)
		(fp_line
			(start 0.7874 -0.4064)
			(end -0.7874 -0.4064)
			(stroke
				(width 0.1524)
				(type default)
			)
			(layer "B.SilkS")
		)
		(fp_line
			(start -0.7874 -0.4064)
			(end -0.7874 0.4064)
			(stroke
				(width 0.1524)
				(type default)
			)
			(layer "B.SilkS")
		)
		(fp_line
			(start 0.7874 0.4064)
			(end 0.7874 -0.4064)
			(stroke
				(width 0.1524)
				(type default)
			)
			(layer "B.SilkS")
		)
		(fp_line
			(start -0.7874 0.4064)
			(end 0.7874 0.4064)
			(stroke
				(width 0.1524)
				(type default)
			)
			(layer "B.SilkS")
		)
		(fp_line
			(start 0.67945 -0.305054)
			(end 0.12065 -0.305054)
			(stroke
				(width 0.1)
				(type default)
			)
			(layer "B.Fab")
		)
		(fp_line
			(start 0.12065 -0.305054)
			(end 0.12065 -0.2794)
			(stroke
				(width 0.1)
				(type default)
			)
			(layer "B.Fab")
		)
		(fp_line
			(start -0.12065 -0.3048)
			(end -0.67945 -0.3048)
			(stroke
				(width 0.1)
				(type default)
			)
			(layer "B.Fab")
		)
		(fp_line
			(start -0.67945 -0.3048)
			(end -0.67945 0.3048)
			(stroke
				(width 0.1)
				(type default)
			)
			(layer "B.Fab")
		)
		(fp_line
			(start 0.12065 -0.2794)
			(end -0.12065 -0.2794)
			(stroke
				(width 0.1)
				(type default)
			)
			(layer "B.Fab")
		)
		(fp_line
			(start -0.12065 -0.2794)
			(end -0.12065 -0.3048)
			(stroke
				(width 0.1)
				(type default)
			)
			(layer "B.Fab")
		)
		(fp_line
			(start 0.12065 0.2794)
			(end 0.12065 0.3048)
			(stroke
				(width 0.1)
				(type default)
			)
			(layer "B.Fab")
		)
		(fp_line
			(start -0.120396 0.2794)
			(end 0.12065 0.2794)
			(stroke
				(width 0.1)
				(type default)
			)
			(layer "B.Fab")
		)
		(fp_line
			(start 0.67945 0.3048)
			(end 0.67945 -0.305054)
			(stroke
				(width 0.1)
				(type default)
			)
			(layer "B.Fab")
		)
		(fp_line
			(start 0.12065 0.3048)
			(end 0.67945 0.3048)
			(stroke
				(width 0.1)
				(type default)
			)
			(layer "B.Fab")
		)
		(fp_line
			(start -0.120396 0.3048)
			(end -0.120396 0.2794)
			(stroke
				(width 0.1)
				(type default)
			)
			(layer "B.Fab")
		)
		(fp_line
			(start -0.67945 0.3048)
			(end -0.120396 0.3048)
			(stroke
				(width 0.1)
				(type default)
			)
			(layer "B.Fab")
		)
		(pad "1" smd circle
			(at 0.40005 0 270)
			(size 0 0)
			(layers "B.Cu" "B.Mask" "B.Paste")
			(net "RST_GPU_PERST_0_N")
		)
		(pad "2" smd circle
			(at -0.40005 0 270)
			(size 0 0)
			(layers "B.Cu" "B.Mask" "B.Paste")
			(net "RST_GPU_PERST_0_R_N")
		)
	)
	(footprint ""
		(layer "B.Cu")
		(at 276.649688 -299.224954)
		(property "Reference" "C3355"
			(at 0 0 0)
			(layer "B.SilkS")
			(hide yes)
			(effects
				(font
					(size 1.27 1.27)
				)
				(justify mirror)
			)
		)
		(property "Value" ""
			(at 0 0 0)
			(layer "B.Fab")
			(effects
				(font
					(size 1.27 1.27)
				)
				(justify mirror)
			)
		)
		(duplicate_pad_numbers_are_jumpers no)
		(fp_line
			(start -0.299974 -0.150114)
			(end -0.299974 0.150114)
			(stroke
				(width 0.1)
				(type default)
			)
			(layer "B.Fab")
		)
		(fp_line
			(start -0.299974 0.150114)
			(end 0.299974 0.150114)
			(stroke
				(width 0.1)
				(type default)
			)
			(layer "B.Fab")
		)
		(fp_line
			(start 0.299974 -0.150114)
			(end -0.299974 -0.150114)
			(stroke
				(width 0.1)
				(type default)
			)
			(layer "B.Fab")
		)
		(fp_line
			(start 0.299974 0.150114)
			(end 0.299974 -0.150114)
			(stroke
				(width 0.1)
				(type default)
			)
			(layer "B.Fab")
		)
		(pad "1" smd rect
			(at 0.2667 0 180)
			(size 0.3048 0.381)
			(layers "B.Cu" "B.Mask" "B.Paste")
			(net "P1V8_VDDA_PEX2")
		)
		(pad "2" smd rect
			(at -0.2667 0 180)
			(size 0.3048 0.381)
			(layers "B.Cu" "B.Mask" "B.Paste")
			(net "GND")
		)
	)
	(footprint ""
		(layer "B.Cu")
		(at 131.389882 -183.790082)
		(property "Reference" "R1082"
			(at 0 0 0)
			(layer "B.SilkS")
			(hide yes)
			(effects
				(font
					(size 1.27 1.27)
				)
				(justify mirror)
			)
		)
		(property "Value" ""
			(at 0 0 0)
			(layer "B.Fab")
			(effects
				(font
					(size 1.27 1.27)
				)
				(justify mirror)
			)
		)
		(duplicate_pad_numbers_are_jumpers no)
		(fp_line
			(start -1.2954 -0.5842)
			(end -1.2954 0.5842)
			(stroke
				(width 0.1524)
				(type default)
			)
			(layer "B.SilkS")
		)
		(fp_line
			(start -1.2954 0.5842)
			(end 1.2954 0.5842)
			(stroke
				(width 0.1524)
				(type default)
			)
			(layer "B.SilkS")
		)
		(fp_line
			(start 1.2954 -0.5842)
			(end -1.2954 -0.5842)
			(stroke
				(width 0.1524)
				(type default)
			)
			(layer "B.SilkS")
		)
		(fp_line
			(start 1.2954 0.5842)
			(end 1.2954 -0.5842)
			(stroke
				(width 0.1524)
				(type default)
			)
			(layer "B.SilkS")
		)
		(fp_line
			(start -1.1938 -0.406654)
			(end -1.1938 0.4064)
			(stroke
				(width 0.1)
				(type default)
			)
			(layer "B.Fab")
		)
		(fp_line
			(start -1.1938 0.4064)
			(end -0.8636 0.4064)
			(stroke
				(width 0.1)
				(type default)
			)
			(layer "B.Fab")
		)
		(fp_line
			(start -0.8636 -0.4572)
			(end -0.8636 -0.406654)
			(stroke
				(width 0.1)
				(type default)
			)
			(layer "B.Fab")
		)
		(fp_line
			(start -0.8636 -0.406654)
			(end -1.1938 -0.406654)
			(stroke
				(width 0.1)
				(type default)
			)
			(layer "B.Fab")
		)
		(fp_line
			(start -0.8636 0.4064)
			(end -0.8636 0.4572)
			(stroke
				(width 0.1)
				(type default)
			)
			(layer "B.Fab")
		)
		(fp_line
			(start -0.8636 0.4572)
			(end 0.8636 0.4572)
			(stroke
				(width 0.1)
				(type default)
			)
			(layer "B.Fab")
		)
		(fp_line
			(start 0.8636 -0.4572)
			(end -0.8636 -0.4572)
			(stroke
				(width 0.1)
				(type default)
			)
			(layer "B.Fab")
		)
		(fp_line
			(start 0.8636 -0.406654)
			(end 0.8636 -0.4572)
			(stroke
				(width 0.1)
				(type default)
			)
			(layer "B.Fab")
		)
		(fp_line
			(start 0.8636 0.4064)
			(end 1.1938 0.4064)
			(stroke
				(width 0.1)
				(type default)
			)
			(layer "B.Fab")
		)
		(fp_line
			(start 0.8636 0.4318)
			(end 0.8636 0.4064)
			(stroke
				(width 0.1)
				(type default)
			)
			(layer "B.Fab")
		)
		(fp_line
			(start 0.8636 0.4572)
			(end 0.8636 0.4318)
			(stroke
				(width 0.1)
				(type default)
			)
			(layer "B.Fab")
		)
		(fp_line
			(start 1.1938 -0.406654)
			(end 0.8636 -0.406654)
			(stroke
				(width 0.1)
				(type default)
			)
			(layer "B.Fab")
		)
		(fp_line
			(start 1.1938 0.4064)
			(end 1.1938 -0.406654)
			(stroke
				(width 0.1)
				(type default)
			)
			(layer "B.Fab")
		)
		(pad "1" smd rect
			(at 0.7366 0 270)
			(size 0.7112 0.8128)
			(layers "B.Cu" "B.Mask" "B.Paste")
			(net "P3V3_DB2000QL_VDDA")
		)
		(pad "2" smd rect
			(at -0.7366 0 270)
			(size 0.7112 0.8128)
			(layers "B.Cu" "B.Mask" "B.Paste")
			(net "P3V3_DB2000QL_FB_VDD")
		)
	)
	(footprint ""
		(layer "B.Cu")
		(at 289.94989 -290.199826 90)
		(property "Reference" "C1750"
			(at 0 0 90)
			(layer "B.SilkS")
			(hide yes)
			(effects
				(font
					(size 1.27 1.27)
				)
				(justify mirror)
			)
		)
		(property "Value" ""
			(at 0 0 90)
			(layer "B.Fab")
			(effects
				(font
					(size 1.27 1.27)
				)
				(justify mirror)
			)
		)
		(duplicate_pad_numbers_are_jumpers no)
		(fp_line
			(start 0.299974 -0.150114)
			(end -0.299974 -0.150114)
			(stroke
				(width 0.1)
				(type default)
			)
			(layer "B.Fab")
		)
		(fp_line
			(start -0.299974 -0.150114)
			(end -0.299974 0.150114)
			(stroke
				(width 0.1)
				(type default)
			)
			(layer "B.Fab")
		)
		(fp_line
			(start 0.299974 0.150114)
			(end 0.299974 -0.150114)
			(stroke
				(width 0.1)
				(type default)
			)
			(layer "B.Fab")
		)
		(fp_line
			(start -0.299974 0.150114)
			(end 0.299974 0.150114)
			(stroke
				(width 0.1)
				(type default)
			)
			(layer "B.Fab")
		)
		(pad "1" smd rect
			(at 0.2667 0 270)
			(size 0.3048 0.381)
			(layers "B.Cu" "B.Mask" "B.Paste")
			(net "P0V8_SERDES_VDDA_PEX2")
		)
		(pad "2" smd rect
			(at -0.2667 0 270)
			(size 0.3048 0.381)
			(layers "B.Cu" "B.Mask" "B.Paste")
			(net "GND")
		)
	)
)
